(kicad_pcb
	(version 20260206)
	(generator "pcbnew")
	(generator_version "10.0")
	(general
		(thickness 1.6)
		(legacy_teardrops no)
	)
	(paper "A4")
	(title_block
		(title "netronome-mezz — pcbd0082-001_rev01_jul9_a.brd")
		(comment 1 "Open CloudServer (Microsoft) / footprints 603-607 of 714")
	)
	(layers
		(0 "F.Cu" signal "TOP")
		(4 "In1.Cu" signal "02_GND")
		(6 "In2.Cu" signal "03_SIG")
		(8 "In3.Cu" signal "04_SIG")
		(10 "In4.Cu" signal "05_GND")
		(12 "In5.Cu" signal "06_PWR1")
		(14 "In6.Cu" signal "07_SIG")
		(16 "In7.Cu" signal "08_SIG")
		(18 "In8.Cu" signal "09_GND")
		(2 "B.Cu" signal "BOTTOM")
		(9 "F.Adhes" user "F.Adhesive")
		(11 "B.Adhes" user "B.Adhesive")
		(13 "F.Paste" user "Package Geometry/Pastemask Top")
		(15 "B.Paste" user "Package Geometry/Pastemask Bottom")
		(5 "F.SilkS" user "Ref Des/Silkscreen Top")
		(7 "B.SilkS" user "Ref Des/Silkscreen Bottom")
		(1 "F.Mask" user "Board Geometry/Soldermask Top")
		(3 "B.Mask" user "Board Geometry/Soldermask Bottom")
		(17 "Dwgs.User" user "User.Drawings")
		(19 "Cmts.User" user "User.Comments")
		(21 "Eco1.User" user "User.Eco1")
		(23 "Eco2.User" user "User.Eco2")
		(25 "Edge.Cuts" user "Board Geometry/Outline")
		(27 "Margin" user)
		(31 "F.CrtYd" user "Package Geometry/Place Bound Top")
		(29 "B.CrtYd" user "Package Geometry/Place Bound Bottom")
		(35 "F.Fab" user "Ref Des/Assembly Top")
		(33 "B.Fab" user "Ref Des/Assembly Bottom")
		(45 "User.4" user "COMPVAL_TYPE_BOTTOM")
	)
	(footprint ""
		(layer "B.Cu")
		(at 48.768 4.445 180)
		(property "Reference" "C280"
			(at -0.98933 -0.508 270)
			(unlocked yes)
			(layer "B.SilkS")
			(effects
				(font
					(size 0.7874 0.5842)
					(thickness 0.127)
				)
				(justify left mirror)
			)
		)
		(property "Value" "22UF"
			(at 0.148158 1.7526 90)
			(unlocked yes)
			(layer "B.Fab")
			(hide yes)
			(effects
				(font
					(size 1.27 0.9652)
					(thickness 0.000001)
				)
				(justify left mirror)
			)
		)
		(property "Device Type" "CAPC0063"
			(at 0.148158 1.7526 90)
			(unlocked yes)
			(layer "B.Fab")
			(hide yes)
			(effects
				(font
					(size 1.27 0.9652)
					(thickness 0.000001)
				)
				(justify left mirror)
			)
		)
		(duplicate_pad_numbers_are_jumpers no)
		(fp_circle
			(center 0 0)
			(end -0.127 0)
			(stroke
				(width 0.2032)
				(type default)
			)
			(fill no)
			(layer "B.SilkS")
		)
		(fp_poly
			(pts
				(xy -0.7874 -1.6637) (xy 0.7874 -1.6637) (xy 0.7874 1.6637) (xy -0.7874 1.6637)
			)
			(stroke
				(width 0)
				(type default)
			)
			(fill no)
			(layer "B.CrtYd")
		)
		(fp_line
			(start 0.4064 0.8128)
			(end 0.4064 -0.7874)
			(stroke
				(width 0.0254)
				(type default)
			)
			(layer "B.Fab")
		)
		(fp_line
			(start 0.4064 -0.7874)
			(end -0.4064 -0.7874)
			(stroke
				(width 0.0254)
				(type default)
			)
			(layer "B.Fab")
		)
		(fp_line
			(start -0.4064 0.8128)
			(end 0.4064 0.8128)
			(stroke
				(width 0.0254)
				(type default)
			)
			(layer "B.Fab")
		)
		(fp_line
			(start -0.4064 -0.7874)
			(end -0.4064 0.8128)
			(stroke
				(width 0.0254)
				(type default)
			)
			(layer "B.Fab")
		)
		(pad "1" smd rect
			(at 0 -0.8001)
			(size 0.8636 0.9652)
			(layers "B.Cu" "B.Mask" "B.Paste")
			(net "VDDA_SERDES")
		)
		(pad "2" smd rect
			(at 0 0.8001)
			(size 0.8636 0.9652)
			(layers "B.Cu" "B.Mask" "B.Paste")
			(net "GND")
		)
		(zone
			(layer "B.Cu")
			(hatch none 0.5)
			(connect_pads
				(clearance 0)
			)
			(min_thickness 0.25)
			(keepout
				(tracks not_allowed)
				(vias allowed)
				(pads allowed)
				(copperpour not_allowed)
				(footprints allowed)
			)
			(placement
				(enabled no)
				(sheetname "")
			)
			(fill
				(thermal_gap 0.5)
				(thermal_bridge_width 0.5)
				(island_removal_mode 0)
			)
			(polygon
				(pts
					(xy 48.7045 4.699) (xy 48.8315 4.699) (xy 48.8315 4.191) (xy 48.7045 4.191)
				)
			)
		)
	)
	(footprint ""
		(layer "B.Cu")
		(at 57.023 47.244)
		(property "Reference" "TP32"
			(at 0.10033 4.064 270)
			(unlocked yes)
			(layer "B.SilkS")
			(effects
				(font
					(size 0.7874 0.5842)
					(thickness 0.127)
				)
				(justify left mirror)
			)
		)
		(property "Value" "*"
			(at 0.4826 -0.14732 0)
			(unlocked yes)
			(layer "B.Fab")
			(hide yes)
			(effects
				(font
					(size 1.27 0.9652)
					(thickness 0.000001)
				)
				(justify left mirror)
			)
		)
		(property "Device Type" "TP_SMALL"
			(at 0.4826 -0.14732 0)
			(unlocked yes)
			(layer "B.Fab")
			(hide yes)
			(effects
				(font
					(size 1.27 0.9652)
					(thickness 0.000001)
				)
				(justify left mirror)
			)
		)
		(duplicate_pad_numbers_are_jumpers no)
		(fp_line
			(start -0.8636 -0.8636)
			(end 0.8636 -0.8636)
			(stroke
				(width 0.1524)
				(type default)
			)
			(layer "B.SilkS")
		)
		(fp_line
			(start -0.8636 0.8636)
			(end -0.8636 -0.8636)
			(stroke
				(width 0.1524)
				(type default)
			)
			(layer "B.SilkS")
		)
		(fp_line
			(start 0.8636 -0.8636)
			(end 0.8636 0.8636)
			(stroke
				(width 0.1524)
				(type default)
			)
			(layer "B.SilkS")
		)
		(fp_line
			(start 0.8636 0.8636)
			(end -0.8636 0.8636)
			(stroke
				(width 0.1524)
				(type default)
			)
			(layer "B.SilkS")
		)
		(fp_poly
			(pts
				(xy 0.635 -0.635) (xy 0.635 0.635) (xy -0.635 0.635) (xy -0.635 -0.635)
			)
			(stroke
				(width 0)
				(type default)
			)
			(fill no)
			(layer "B.CrtYd")
		)
		(pad "1" smd rect
			(at 0 0 180)
			(size 1.27 1.27)
			(layers "B.Cu" "B.Mask" "B.Paste")
			(net "GH_PHASE1")
		)
	)
	(footprint ""
		(layer "B.Cu")
		(at 75.451005 6.698996)
		(property "Reference" "V_A-DQ06"
			(at 0 0 0)
			(layer "B.SilkS")
			(hide yes)
			(effects
				(font
					(size 1.27 1.27)
				)
				(justify mirror)
			)
		)
		(property "Value" ""
			(at 0 0 0)
			(layer "B.Fab")
			(effects
				(font
					(size 1.27 1.27)
				)
				(justify mirror)
			)
		)
		(duplicate_pad_numbers_are_jumpers no)
		(pad "1" thru_hole circle
			(at 0 0 180)
			(size 0.4572 0.4572)
			(drill 0.20574)
			(layers "*.Cu" "*.Mask")
			(remove_unused_layers no)
			(net "DDR0_32A_DQ6")
			(clearance 0.1143)
			(thermal_gap 0.1143)
		)
	)
	(footprint ""
		(layer "B.Cu")
		(at 28.448 25.781)
		(property "Reference" "TP17"
			(at 0.762 1.42367 0)
			(unlocked yes)
			(layer "B.SilkS")
			(effects
				(font
					(size 0.7874 0.5842)
					(thickness 0.127)
				)
				(justify left mirror)
			)
		)
		(property "Value" "*"
			(at 0.4826 -0.14732 0)
			(unlocked yes)
			(layer "B.Fab")
			(hide yes)
			(effects
				(font
					(size 1.27 0.9652)
					(thickness 0.000001)
				)
				(justify left mirror)
			)
		)
		(property "Device Type" "TP_SMALL"
			(at 0.4826 -0.14732 0)
			(unlocked yes)
			(layer "B.Fab")
			(hide yes)
			(effects
				(font
					(size 1.27 0.9652)
					(thickness 0.000001)
				)
				(justify left mirror)
			)
		)
		(duplicate_pad_numbers_are_jumpers no)
		(fp_line
			(start -0.8636 -0.8636)
			(end 0.8636 -0.8636)
			(stroke
				(width 0.1524)
				(type default)
			)
			(layer "B.SilkS")
		)
		(fp_line
			(start -0.8636 0.8636)
			(end -0.8636 -0.8636)
			(stroke
				(width 0.1524)
				(type default)
			)
			(layer "B.SilkS")
		)
		(fp_line
			(start 0.8636 -0.8636)
			(end 0.8636 0.8636)
			(stroke
				(width 0.1524)
				(type default)
			)
			(layer "B.SilkS")
		)
		(fp_line
			(start 0.8636 0.8636)
			(end -0.8636 0.8636)
			(stroke
				(width 0.1524)
				(type default)
			)
			(layer "B.SilkS")
		)
		(fp_poly
			(pts
				(xy 0.635 -0.635) (xy 0.635 0.635) (xy -0.635 0.635) (xy -0.635 -0.635)
			)
			(stroke
				(width 0)
				(type default)
			)
			(fill no)
			(layer "B.CrtYd")
		)
		(pad "1" smd rect
			(at 0 0 180)
			(size 1.27 1.27)
			(layers "B.Cu" "B.Mask" "B.Paste")
			(net "NFP_FAIL_SAFE_BOOT_L")
		)
	)
	(footprint ""
		(layer "B.Cu")
		(at 58.928 37.465 90)
		(property "Reference" "C58"
			(at -1.016 -3.20167 270)
			(unlocked yes)
			(layer "B.SilkS")
			(effects
				(font
					(size 0.7874 0.5842)
					(thickness 0.127)
				)
				(justify left mirror)
			)
		)
		(property "Value" "100UF"
			(at 0.78232 0.4826 0)
			(unlocked yes)
			(layer "B.Fab")
			(hide yes)
			(effects
				(font
					(size 1.27 0.9652)
					(thickness 0.000001)
				)
				(justify left mirror)
			)
		)
		(property "Device Type" "CAPC0087"
			(at 0.78232 0.4826 0)
			(unlocked yes)
			(layer "B.Fab")
			(hide yes)
			(effects
				(font
					(size 1.27 0.9652)
					(thickness 0.000001)
				)
				(justify left mirror)
			)
		)
		(duplicate_pad_numbers_are_jumpers no)
		(fp_circle
			(center 0 0)
			(end 0 0.508)
			(stroke
				(width 0.2032)
				(type default)
			)
			(fill no)
			(layer "B.SilkS")
		)
		(fp_poly
			(pts
				(xy 1.27 2.9464) (xy -1.27 2.9464) (xy -1.27 -2.9464) (xy 1.27 -2.9464)
			)
			(stroke
				(width 0)
				(type default)
			)
			(fill no)
			(layer "B.CrtYd")
		)
		(fp_line
			(start 1.016 -2.794)
			(end -1.016 -2.794)
			(stroke
				(width 0.0254)
				(type default)
			)
			(layer "B.Fab")
		)
		(fp_line
			(start -1.016 -2.794)
			(end -1.016 2.794)
			(stroke
				(width 0.0254)
				(type default)
			)
			(layer "B.Fab")
		)
		(fp_line
			(start 1.016 2.794)
			(end 1.016 -2.794)
			(stroke
				(width 0.0254)
				(type default)
			)
			(layer "B.Fab")
		)
		(fp_line
			(start -1.016 2.794)
			(end 1.016 2.794)
			(stroke
				(width 0.0254)
				(type default)
			)
			(layer "B.Fab")
		)
		(pad "1" smd rect
			(at 0 -1.6764 270)
			(size 1.524 1.524)
			(layers "B.Cu" "B.Mask" "B.Paste")
			(net "VDD_CORE")
		)
		(pad "2" smd rect
			(at 0 1.6764 270)
			(size 1.524 1.524)
			(layers "B.Cu" "B.Mask" "B.Paste")
			(net "GND")
		)
		(zone
			(layer "B.Cu")
			(hatch none 0.5)
			(connect_pads
				(clearance 0)
			)
			(min_thickness 0.25)
			(keepout
				(tracks not_allowed)
				(vias allowed)
				(pads allowed)
				(copperpour not_allowed)
				(footprints allowed)
			)
			(placement
				(enabled no)
				(sheetname "")
			)
			(fill
				(thermal_gap 0.5)
				(thermal_bridge_width 0.5)
				(island_removal_mode 0)
			)
			(polygon
				(pts
					(xy 58.039 36.6776) (xy 58.039 38.2524) (xy 58.1914 38.2524) (xy 58.1914 36.6776)
				)
			)
		)
		(zone
			(layer "B.Cu")
			(hatch none 0.5)
			(connect_pads
				(clearance 0)
			)
			(min_thickness 0.25)
			(keepout
				(tracks not_allowed)
				(vias allowed)
				(pads allowed)
				(copperpour not_allowed)
				(footprints allowed)
			)
			(placement
				(enabled no)
				(sheetname "")
			)
			(fill
				(thermal_gap 0.5)
				(thermal_bridge_width 0.5)
				(island_removal_mode 0)
			)
			(polygon
				(pts
					(xy 59.6646 36.6776) (xy 59.6646 38.2524) (xy 59.817 38.2524) (xy 59.817 36.6776)
				)
			)
		)
		(zone
			(layer "B.Cu")
			(hatch none 0.5)
			(connect_pads
				(clearance 0)
			)
			(min_thickness 0.25)
			(keepout
				(tracks allowed)
				(vias not_allowed)
				(pads allowed)
				(copperpour not_allowed)
				(footprints allowed)
			)
			(placement
				(enabled no)
				(sheetname "")
			)
			(fill
				(thermal_gap 0.5)
				(thermal_bridge_width 0.5)
				(island_removal_mode 0)
			)
			(polygon
				(pts
					(xy 60.5282 36.6776) (xy 60.5282 38.2524) (xy 57.3278 38.2524) (xy 57.3278 36.6776)
				)
			)
		)
	)
)
